(kicad_pcb
	(version 20260206)
	(generator "pcbnew")
	(generator_version "10.0")
	(general
		(thickness 1.6)
		(legacy_teardrops no)
	)
	(paper "A4")
	(title_block
		(title "Wiwynn_Tioga_Pass_MB.brd")
		(comment 1 "Tioga Pass / footprints 4644-4650 of 4770")
	)
	(layers
		(0 "F.Cu" signal "TOP")
		(4 "In1.Cu" signal "L2GND")
		(6 "In2.Cu" signal "L3")
		(8 "In3.Cu" signal "L4GND")
		(10 "In4.Cu" signal "L5")
		(12 "In5.Cu" signal "L6GND")
		(14 "In6.Cu" signal "L7VCC")
		(16 "In7.Cu" signal "L8VCC")
		(18 "In8.Cu" signal "L9GND")
		(20 "In9.Cu" signal "L10")
		(22 "In10.Cu" signal "L11GND")
		(24 "In11.Cu" signal "L12")
		(26 "In12.Cu" signal "L13GND")
		(2 "B.Cu" signal "BOTTOM")
		(9 "F.Adhes" user "F.Adhesive")
		(11 "B.Adhes" user "B.Adhesive")
		(13 "F.Paste" user "Package Geometry/Pastemask Top")
		(15 "B.Paste" user "Package Geometry/Pastemask Bottom")
		(5 "F.SilkS" user "Ref Des/Silkscreen Top")
		(7 "B.SilkS" user "Ref Des/Silkscreen Bottom")
		(1 "F.Mask" user "Board Geometry/Soldermask Top")
		(3 "B.Mask" user "Board Geometry/Soldermask Bottom")
		(17 "Dwgs.User" user "User.Drawings")
		(19 "Cmts.User" user "User.Comments")
		(21 "Eco1.User" user "User.Eco1")
		(23 "Eco2.User" user "User.Eco2")
		(25 "Edge.Cuts" user "Board Geometry/Outline")
		(27 "Margin" user)
		(31 "F.CrtYd" user "Package Geometry/Place Bound Top")
		(29 "B.CrtYd" user "Package Geometry/Place Bound Bottom")
		(35 "F.Fab" user "Ref Des/Assembly Top")
		(33 "B.Fab" user "Ref Des/Assembly Bottom")
	)
	(footprint ""
		(layer "B.Cu")
		(at 332.105 -141.351 90)
		(property "Reference" "C4L5"
			(at -3.07467 8.001 0)
			(unlocked yes)
			(layer "B.SilkS")
			(effects
				(font
					(size 0.7874 0.5842)
					(thickness 0.1524)
				)
				(justify mirror)
			)
		)
		(property "Value" ""
			(at 0 0 90)
			(layer "B.Fab")
			(effects
				(font
					(size 1.27 1.27)
				)
				(justify mirror)
			)
		)
		(duplicate_pad_numbers_are_jumpers no)
		(fp_line
			(start 2.563114 -1.616456)
			(end 2.563114 1.633728)
			(stroke
				(width 0.1524)
				(type default)
			)
			(layer "B.SilkS")
		)
		(fp_line
			(start 1.6002 -1.616456)
			(end 2.563114 -1.616456)
			(stroke
				(width 0.1524)
				(type default)
			)
			(layer "B.SilkS")
		)
		(fp_line
			(start -1.6002 -1.616456)
			(end -2.504948 -1.616456)
			(stroke
				(width 0.1524)
				(type default)
			)
			(layer "B.SilkS")
		)
		(fp_line
			(start -2.504948 -1.616456)
			(end -2.504948 1.633728)
			(stroke
				(width 0.1524)
				(type default)
			)
			(layer "B.SilkS")
		)
		(fp_line
			(start 2.563114 1.633728)
			(end 1.6002 1.633728)
			(stroke
				(width 0.1524)
				(type default)
			)
			(layer "B.SilkS")
		)
		(fp_line
			(start -2.504948 1.633728)
			(end -1.6002 1.633728)
			(stroke
				(width 0.1524)
				(type default)
			)
			(layer "B.SilkS")
		)
		(fp_line
			(start 2.286 7.366)
			(end 2.286 1.632712)
			(stroke
				(width 0.1524)
				(type default)
			)
			(layer "B.SilkS")
		)
		(fp_line
			(start 2.286 7.366)
			(end 1.60147 7.366)
			(stroke
				(width 0.1524)
				(type default)
			)
			(layer "B.SilkS")
		)
		(fp_line
			(start -2.286 7.366)
			(end -2.286 1.63195)
			(stroke
				(width 0.1524)
				(type default)
			)
			(layer "B.SilkS")
		)
		(fp_line
			(start -2.286 7.366)
			(end -1.600708 7.366)
			(stroke
				(width 0.1524)
				(type default)
			)
			(layer "B.SilkS")
		)
		(fp_rect
			(start 2.286 7.366)
			(end -2.286 -0.254)
			(stroke
				(width 0)
				(type default)
			)
			(fill no)
			(layer "B.CrtYd")
		)
		(fp_line
			(start 2.286 -0.254)
			(end -2.286 -0.254)
			(stroke
				(width 0.1)
				(type default)
			)
			(layer "B.Fab")
		)
		(fp_line
			(start -2.286 -0.254)
			(end -2.286 7.366)
			(stroke
				(width 0.1)
				(type default)
			)
			(layer "B.Fab")
		)
		(fp_line
			(start 2.286 7.366)
			(end 2.286 -0.254)
			(stroke
				(width 0.1)
				(type default)
			)
			(layer "B.Fab")
		)
		(fp_line
			(start -2.286 7.366)
			(end 2.286 7.366)
			(stroke
				(width 0.1)
				(type default)
			)
			(layer "B.Fab")
		)
		(pad "1" smd rect
			(at 0 0 270)
			(size 2.54 3.048)
			(layers "B.Cu" "B.Mask" "B.Paste")
			(net "PVDDQ_DEF")
		)
		(pad "2" smd rect
			(at 0 7.112 270)
			(size 2.54 3.048)
			(layers "B.Cu" "B.Mask" "B.Paste")
			(net "GND")
		)
	)
	(footprint ""
		(layer "B.Cu")
		(at 388.239 -105.918 180)
		(property "Reference" "C3N21"
			(at 0 0 0)
			(layer "B.SilkS")
			(hide yes)
			(effects
				(font
					(size 1.27 1.27)
				)
				(justify mirror)
			)
		)
		(property "Value" ""
			(at 0 0 0)
			(layer "B.Fab")
			(effects
				(font
					(size 1.27 1.27)
				)
				(justify mirror)
			)
		)
		(duplicate_pad_numbers_are_jumpers no)
		(fp_poly
			(pts
				(xy -0.3048 -0.1016) (xy -0.3048 0.9906) (xy 0.3048 0.9906) (xy 0.3048 -0.1016)
			)
			(stroke
				(width 0)
				(type default)
			)
			(fill no)
			(layer "B.CrtYd")
		)
		(fp_line
			(start 0.3048 0.9906)
			(end -0.3048 0.9906)
			(stroke
				(width 0.1)
				(type default)
			)
			(layer "B.Fab")
		)
		(fp_line
			(start 0.3048 -0.1016)
			(end 0.3048 0.9906)
			(stroke
				(width 0.1)
				(type default)
			)
			(layer "B.Fab")
		)
		(fp_line
			(start -0.3048 0.9906)
			(end -0.3048 -0.1016)
			(stroke
				(width 0.1)
				(type default)
			)
			(layer "B.Fab")
		)
		(fp_line
			(start -0.3048 -0.1016)
			(end 0.3048 -0.1016)
			(stroke
				(width 0.1)
				(type default)
			)
			(layer "B.Fab")
		)
		(pad "1" smd rect
			(at 0 0)
			(size 0.508 0.508)
			(layers "B.Cu" "B.Mask" "B.Paste")
			(net "P1V8_PCH_STBY")
		)
		(pad "2" smd rect
			(at 0 0.889)
			(size 0.508 0.508)
			(layers "B.Cu" "B.Mask" "B.Paste")
			(net "GND")
		)
		(zone
			(layer "B.Cu")
			(hatch none 0.5)
			(connect_pads
				(clearance 0)
			)
			(min_thickness 0.25)
			(keepout
				(tracks not_allowed)
				(vias allowed)
				(pads allowed)
				(copperpour not_allowed)
				(footprints allowed)
			)
			(placement
				(enabled no)
				(sheetname "")
			)
			(fill
				(thermal_gap 0.5)
				(thermal_bridge_width 0.5)
				(island_removal_mode 0)
			)
			(polygon
				(pts
					(xy 387.985 -106.553) (xy 388.493 -106.553) (xy 388.493 -106.172) (xy 387.985 -106.172)
				)
			)
		)
		(zone
			(layer "B.Cu")
			(hatch none 0.5)
			(connect_pads
				(clearance 0)
			)
			(min_thickness 0.25)
			(keepout
				(tracks allowed)
				(vias not_allowed)
				(pads allowed)
				(copperpour not_allowed)
				(footprints allowed)
			)
			(placement
				(enabled no)
				(sheetname "")
			)
			(fill
				(thermal_gap 0.5)
				(thermal_bridge_width 0.5)
				(island_removal_mode 0)
			)
			(polygon
				(pts
					(xy 387.985 -106.172) (xy 388.493 -106.172) (xy 388.493 -106.553) (xy 387.985 -106.553)
				)
			)
		)
	)
	(footprint ""
		(layer "B.Cu")
		(at 349.133414 -126.345442 -90)
		(property "Reference" "R769"
			(at 0.8382 -0.67818 270)
			(unlocked yes)
			(layer "B.SilkS")
			(effects
				(font
					(size 0.4064 0.254)
					(thickness 0.1524)
				)
				(justify left mirror)
			)
		)
		(property "Value" ""
			(at 0 0 90)
			(layer "B.Fab")
			(effects
				(font
					(size 1.27 1.27)
				)
				(justify mirror)
			)
		)
		(duplicate_pad_numbers_are_jumpers no)
		(fp_poly
			(pts
				(xy 0.2794 -0.1016) (xy -0.2794 -0.1016) (xy -0.2794 0.9906) (xy 0.2794 0.9906)
			)
			(stroke
				(width 0)
				(type default)
			)
			(fill no)
			(layer "B.CrtYd")
		)
		(fp_line
			(start -0.2794 0.9906)
			(end -0.2794 -0.1016)
			(stroke
				(width 0.1)
				(type default)
			)
			(layer "B.Fab")
		)
		(fp_line
			(start 0.2794 0.9906)
			(end -0.2794 0.9906)
			(stroke
				(width 0.1)
				(type default)
			)
			(layer "B.Fab")
		)
		(fp_line
			(start -0.2794 -0.1016)
			(end 0.2794 -0.1016)
			(stroke
				(width 0.1)
				(type default)
			)
			(layer "B.Fab")
		)
		(fp_line
			(start 0.2794 -0.1016)
			(end 0.2794 0.9906)
			(stroke
				(width 0.1)
				(type default)
			)
			(layer "B.Fab")
		)
		(pad "1" smd rect
			(at 0 0 90)
			(size 0.508 0.508)
			(layers "B.Cu" "B.Mask" "B.Paste")
			(net "P3E_CPU0_PE1_PCH_RXP<14>")
		)
		(pad "2" smd rect
			(at 0 0.889 90)
			(size 0.508 0.508)
			(layers "B.Cu" "B.Mask" "B.Paste")
			(net "P3E_CPU0_PE1_PCH_CON_RXP<14>")
		)
		(zone
			(layer "B.Cu")
			(hatch none 0.5)
			(connect_pads
				(clearance 0)
			)
			(min_thickness 0.25)
			(keepout
				(tracks not_allowed)
				(vias allowed)
				(pads allowed)
				(copperpour not_allowed)
				(footprints allowed)
			)
			(placement
				(enabled no)
				(sheetname "")
			)
			(fill
				(thermal_gap 0.5)
				(thermal_bridge_width 0.5)
				(island_removal_mode 0)
			)
			(polygon
				(pts
					(xy 348.498414 -126.091442) (xy 348.498414 -126.599442) (xy 348.879414 -126.599442) (xy 348.879414 -126.091442)
				)
			)
		)
		(zone
			(layer "B.Cu")
			(hatch none 0.5)
			(connect_pads
				(clearance 0)
			)
			(min_thickness 0.25)
			(keepout
				(tracks allowed)
				(vias not_allowed)
				(pads allowed)
				(copperpour not_allowed)
				(footprints allowed)
			)
			(placement
				(enabled no)
				(sheetname "")
			)
			(fill
				(thermal_gap 0.5)
				(thermal_bridge_width 0.5)
				(island_removal_mode 0)
			)
			(polygon
				(pts
					(xy 348.879414 -126.091442) (xy 348.879414 -126.599442) (xy 348.498414 -126.599442) (xy 348.498414 -126.091442)
				)
			)
		)
	)
	(footprint ""
		(layer "B.Cu")
		(at 370.078 -26.162)
		(property "Reference" "RN8F6"
			(at 0 0 0)
			(layer "B.SilkS")
			(hide yes)
			(effects
				(font
					(size 1.27 1.27)
				)
				(justify mirror)
			)
		)
		(property "Value" "*"
			(at -0.064008 -4.108196 0)
			(unlocked yes)
			(layer "B.Fab")
			(hide yes)
			(effects
				(font
					(size 1.27 1.016)
					(thickness 0.1524)
				)
				(justify mirror)
			)
		)
		(property "Device Type" "82KR2F-1-GP_SMD-RG-82KR2F-1-GPA"
			(at -0.064008 -5.632196 0)
			(unlocked yes)
			(layer "B.Fab")
			(hide yes)
			(effects
				(font
					(size 1.27 1.016)
					(thickness 0.1524)
				)
				(justify mirror)
			)
		)
		(duplicate_pad_numbers_are_jumpers no)
		(fp_line
			(start -0.508 -0.9398)
			(end 0.508 -0.9398)
			(stroke
				(width 0.1524)
				(type default)
			)
			(layer "B.SilkS")
		)
		(fp_line
			(start 0.508 -0.9398)
			(end 0.508 0.9398)
			(stroke
				(width 0.1524)
				(type default)
			)
			(layer "B.SilkS")
		)
		(fp_rect
			(start 0.508 0.9398)
			(end -0.508 -0.9398)
			(stroke
				(width 0)
				(type default)
			)
			(fill no)
			(layer "B.CrtYd")
		)
		(fp_rect
			(start 0.508 0.9398)
			(end -0.508 -0.9398)
			(stroke
				(width 0)
				(type default)
			)
			(fill no)
			(layer "B.Fab")
		)
		(pad "1" smd custom
			(at 0 -0.4445 180)
			(size 0.1397 0.1397)
			(layers "B.Cu" "B.Mask" "B.Paste")
			(net "TPM_SPI_BMC_WP_N")
			(options
				(clearance outline)
				(anchor circle)
			)
			(primitives
				(gr_poly
					(pts
						(arc
							(start -0.1778 0.2794)
							(mid -0.249642 0.249642)
							(end -0.2794 0.1778)
						)
						(arc
							(start -0.2794 -0.1778)
							(mid -0.249642 -0.249642)
							(end -0.1778 -0.2794)
						)
						(arc
							(start 0.1778 -0.2794)
							(mid 0.249642 -0.249642)
							(end 0.2794 -0.1778)
						)
						(arc
							(start 0.2794 0.1778)
							(mid 0.249642 0.249642)
							(end 0.1778 0.2794)
						)
					)
					(width 0)
					(fill yes)
				)
			)
		)
		(pad "2" smd custom
			(at 0 0.4445 180)
			(size 0.1397 0.1397)
			(layers "B.Cu" "B.Mask" "B.Paste")
			(net "GND")
			(options
				(clearance outline)
				(anchor circle)
			)
			(primitives
				(gr_poly
					(pts
						(arc
							(start -0.1778 0.2794)
							(mid -0.249642 0.249642)
							(end -0.2794 0.1778)
						)
						(arc
							(start -0.2794 -0.1778)
							(mid -0.249642 -0.249642)
							(end -0.1778 -0.2794)
						)
						(arc
							(start 0.1778 -0.2794)
							(mid 0.249642 -0.249642)
							(end 0.2794 -0.1778)
						)
						(arc
							(start 0.2794 0.1778)
							(mid 0.249642 0.249642)
							(end 0.1778 0.2794)
						)
					)
					(width 0)
					(fill yes)
				)
			)
		)
	)
	(footprint ""
		(layer "B.Cu")
		(at 437.7944 -50.4698 90)
		(property "Reference" "R2R8"
			(at 0 0 90)
			(layer "B.SilkS")
			(hide yes)
			(effects
				(font
					(size 1.27 1.27)
				)
				(justify mirror)
			)
		)
		(property "Value" "*"
			(at -0.064008 -4.108196 90)
			(unlocked yes)
			(layer "B.Fab")
			(hide yes)
			(effects
				(font
					(size 1.27 1.016)
					(thickness 0.1524)
				)
				(justify mirror)
			)
		)
		(property "Device Type" "887R2F-L-GP_SMD-RG-887R2F-L-GPA"
			(at -0.064008 -5.632196 90)
			(unlocked yes)
			(layer "B.Fab")
			(hide yes)
			(effects
				(font
					(size 1.27 1.016)
					(thickness 0.1524)
				)
				(justify mirror)
			)
		)
		(duplicate_pad_numbers_are_jumpers no)
		(fp_line
			(start 0.508 -0.9398)
			(end 0.508 0.9398)
			(stroke
				(width 0.1524)
				(type default)
			)
			(layer "B.SilkS")
		)
		(fp_line
			(start -0.508 -0.9398)
			(end 0.508 -0.9398)
			(stroke
				(width 0.1524)
				(type default)
			)
			(layer "B.SilkS")
		)
		(fp_rect
			(start 0.508 0.9398)
			(end -0.508 -0.9398)
			(stroke
				(width 0)
				(type default)
			)
			(fill no)
			(layer "B.CrtYd")
		)
		(fp_rect
			(start 0.508 0.9398)
			(end -0.508 -0.9398)
			(stroke
				(width 0)
				(type default)
			)
			(fill no)
			(layer "B.Fab")
		)
		(pad "1" smd custom
			(at 0 -0.4445 270)
			(size 0.1397 0.1397)
			(layers "B.Cu" "B.Mask" "B.Paste")
			(net "FM_MEZZB_PRSNT1_N")
			(options
				(clearance outline)
				(anchor circle)
			)
			(primitives
				(gr_poly
					(pts
						(arc
							(start -0.1778 0.2794)
							(mid -0.249642 0.249642)
							(end -0.2794 0.1778)
						)
						(arc
							(start -0.2794 -0.1778)
							(mid -0.249642 -0.249642)
							(end -0.1778 -0.2794)
						)
						(arc
							(start 0.1778 -0.2794)
							(mid 0.249642 -0.249642)
							(end 0.2794 -0.1778)
						)
						(arc
							(start 0.2794 0.1778)
							(mid 0.249642 0.249642)
							(end 0.1778 0.2794)
						)
					)
					(width 0)
					(fill yes)
				)
			)
		)
		(pad "2" smd custom
			(at 0 0.4445 270)
			(size 0.1397 0.1397)
			(layers "B.Cu" "B.Mask" "B.Paste")
			(net "GND")
			(options
				(clearance outline)
				(anchor circle)
			)
			(primitives
				(gr_poly
					(pts
						(arc
							(start -0.1778 0.2794)
							(mid -0.249642 0.249642)
							(end -0.2794 0.1778)
						)
						(arc
							(start -0.2794 -0.1778)
							(mid -0.249642 -0.249642)
							(end -0.1778 -0.2794)
						)
						(arc
							(start 0.1778 -0.2794)
							(mid 0.249642 -0.249642)
							(end 0.2794 -0.1778)
						)
						(arc
							(start 0.2794 0.1778)
							(mid 0.249642 0.249642)
							(end 0.1778 0.2794)
						)
					)
					(width 0)
					(fill yes)
				)
			)
		)
	)
	(footprint ""
		(layer "B.Cu")
		(at 198.803768 -77.613002 90)
		(property "Reference" "C4D6"
			(at 0 0 90)
			(layer "B.SilkS")
			(hide yes)
			(effects
				(font
					(size 1.27 1.27)
				)
				(justify mirror)
			)
		)
		(property "Value" "*"
			(at -1.1811 -2.8194 90)
			(unlocked yes)
			(layer "B.Fab")
			(hide yes)
			(effects
				(font
					(size 1.27 1.016)
					(thickness 0.1524)
				)
				(justify mirror)
			)
		)
		(property "Device Type" "SC1U10V2KX-4-GP_SMD-BCG6-SC1U1A"
			(at -1.1811 -4.3434 90)
			(unlocked yes)
			(layer "B.Fab")
			(hide yes)
			(effects
				(font
					(size 1.27 1.016)
					(thickness 0.1524)
				)
				(justify mirror)
			)
		)
		(duplicate_pad_numbers_are_jumpers no)
		(fp_rect
			(start 0.4318 0.9525)
			(end -0.4318 -0.9525)
			(stroke
				(width 0)
				(type default)
			)
			(fill no)
			(layer "B.CrtYd")
		)
		(fp_rect
			(start 0.4318 0.9525)
			(end -0.4318 -0.9525)
			(stroke
				(width 0)
				(type default)
			)
			(fill no)
			(layer "B.Fab")
		)
		(pad "1" smd custom
			(at 0 -0.4445 270)
			(size 0.1524 0.1524)
			(layers "B.Cu" "B.Mask" "B.Paste")
			(net "P5V_STBY")
			(options
				(clearance outline)
				(anchor circle)
			)
			(primitives
				(gr_poly
					(pts
						(arc
							(start 0.3048 0.2032)
							(mid 0.275042 0.275042)
							(end 0.2032 0.3048)
						)
						(arc
							(start -0.2032 0.3048)
							(mid -0.275042 0.275042)
							(end -0.3048 0.2032)
						)
						(arc
							(start -0.3048 -0.2032)
							(mid -0.275042 -0.275042)
							(end -0.2032 -0.3048)
						)
						(arc
							(start 0.2032 -0.3048)
							(mid 0.275042 -0.275042)
							(end 0.3048 -0.2032)
						)
					)
					(width 0)
					(fill yes)
				)
			)
		)
		(pad "2" smd custom
			(at 0 0.4445 270)
			(size 0.1524 0.1524)
			(layers "B.Cu" "B.Mask" "B.Paste")
			(net "GND")
			(options
				(clearance outline)
				(anchor circle)
			)
			(primitives
				(gr_poly
					(pts
						(arc
							(start 0.3048 0.2032)
							(mid 0.275042 0.275042)
							(end 0.2032 0.3048)
						)
						(arc
							(start -0.2032 0.3048)
							(mid -0.275042 0.275042)
							(end -0.3048 0.2032)
						)
						(arc
							(start -0.3048 -0.2032)
							(mid -0.275042 -0.275042)
							(end -0.2032 -0.3048)
						)
						(arc
							(start 0.2032 -0.3048)
							(mid 0.275042 -0.275042)
							(end 0.3048 -0.2032)
						)
					)
					(width 0)
					(fill yes)
				)
			)
		)
	)
	(footprint ""
		(layer "B.Cu")
		(at 210.847432 -67.945 -90)
		(property "Reference" "C6P23"
			(at 0.53467 -4.036568 0)
			(unlocked yes)
			(layer "B.SilkS")
			(effects
				(font
					(size 0.7874 0.5842)
					(thickness 0.1524)
				)
				(justify mirror)
			)
		)
		(property "Value" ""
			(at 0 0 90)
			(layer "B.Fab")
			(effects
				(font
					(size 1.27 1.27)
				)
				(justify mirror)
			)
		)
		(duplicate_pad_numbers_are_jumpers no)
		(fp_line
			(start -2.286 7.366)
			(end -1.600708 7.366)
			(stroke
				(width 0.1524)
				(type default)
			)
			(layer "B.SilkS")
		)
		(fp_line
			(start -2.286 7.366)
			(end -2.286 1.63195)
			(stroke
				(width 0.1524)
				(type default)
			)
			(layer "B.SilkS")
		)
		(fp_line
			(start 2.286 7.366)
			(end 1.60147 7.366)
			(stroke
				(width 0.1524)
				(type default)
			)
			(layer "B.SilkS")
		)
		(fp_line
			(start 2.286 7.366)
			(end 2.286 1.632712)
			(stroke
				(width 0.1524)
				(type default)
			)
			(layer "B.SilkS")
		)
		(fp_line
			(start -2.504948 1.633728)
			(end -1.6002 1.633728)
			(stroke
				(width 0.1524)
				(type default)
			)
			(layer "B.SilkS")
		)
		(fp_line
			(start 2.563114 1.633728)
			(end 1.6002 1.633728)
			(stroke
				(width 0.1524)
				(type default)
			)
			(layer "B.SilkS")
		)
		(fp_line
			(start -2.504948 -1.616456)
			(end -2.504948 1.633728)
			(stroke
				(width 0.1524)
				(type default)
			)
			(layer "B.SilkS")
		)
		(fp_line
			(start -1.6002 -1.616456)
			(end -2.504948 -1.616456)
			(stroke
				(width 0.1524)
				(type default)
			)
			(layer "B.SilkS")
		)
		(fp_line
			(start 1.6002 -1.616456)
			(end 2.563114 -1.616456)
			(stroke
				(width 0.1524)
				(type default)
			)
			(layer "B.SilkS")
		)
		(fp_line
			(start 2.563114 -1.616456)
			(end 2.563114 1.633728)
			(stroke
				(width 0.1524)
				(type default)
			)
			(layer "B.SilkS")
		)
		(fp_rect
			(start 2.286 7.366)
			(end -2.286 -0.254)
			(stroke
				(width 0)
				(type default)
			)
			(fill no)
			(layer "B.CrtYd")
		)
		(fp_line
			(start -2.286 7.366)
			(end 2.286 7.366)
			(stroke
				(width 0.1)
				(type default)
			)
			(layer "B.Fab")
		)
		(fp_line
			(start 2.286 7.366)
			(end 2.286 -0.254)
			(stroke
				(width 0.1)
				(type default)
			)
			(layer "B.Fab")
		)
		(fp_line
			(start -2.286 -0.254)
			(end -2.286 7.366)
			(stroke
				(width 0.1)
				(type default)
			)
			(layer "B.Fab")
		)
		(fp_line
			(start 2.286 -0.254)
			(end -2.286 -0.254)
			(stroke
				(width 0.1)
				(type default)
			)
			(layer "B.Fab")
		)
		(pad "1" smd rect
			(at 0 0 90)
			(size 2.54 3.048)
			(layers "B.Cu" "B.Mask" "B.Paste")
			(net "PVCCIN_CPU0")
		)
		(pad "2" smd rect
			(at 0 7.112 90)
			(size 2.54 3.048)
			(layers "B.Cu" "B.Mask" "B.Paste")
			(net "GND")
		)
	)
)
